(kicad_pcb
	(version 20260206)
	(generator "pcbnew")
	(generator_version "10.0")
	(general
		(thickness 1.6)
		(legacy_teardrops no)
	)
	(paper "A4")
	(title_block
		(title "dpb — 14545-sa.0730WZS0815.brd")
		(comment 1 "Honey Badger (Wiwynn) / footprints 726-733 of 1066")
	)
	(layers
		(0 "F.Cu" signal "TOP")
		(4 "In1.Cu" signal "L2GND")
		(6 "In2.Cu" signal "L3")
		(8 "In3.Cu" signal "L4VCC")
		(10 "In4.Cu" signal "L5VCC")
		(12 "In5.Cu" signal "L6")
		(14 "In6.Cu" signal "L7GND")
		(2 "B.Cu" signal "BOTTOM")
		(9 "F.Adhes" user "F.Adhesive")
		(11 "B.Adhes" user "B.Adhesive")
		(13 "F.Paste" user "Package Geometry/Pastemask Top")
		(15 "B.Paste" user "Package Geometry/Pastemask Bottom")
		(5 "F.SilkS" user "Ref Des/Silkscreen Top")
		(7 "B.SilkS" user "Ref Des/Silkscreen Bottom")
		(1 "F.Mask" user "Board Geometry/Soldermask Top")
		(3 "B.Mask" user "Board Geometry/Soldermask Bottom")
		(17 "Dwgs.User" user "User.Drawings")
		(19 "Cmts.User" user "User.Comments")
		(21 "Eco1.User" user "User.Eco1")
		(23 "Eco2.User" user "User.Eco2")
		(25 "Edge.Cuts" user "Board Geometry/Outline")
		(27 "Margin" user)
		(31 "F.CrtYd" user "Package Geometry/Place Bound Top")
		(29 "B.CrtYd" user "Package Geometry/Place Bound Bottom")
		(35 "F.Fab" user "Ref Des/Assembly Top")
		(33 "B.Fab" user "Ref Des/Assembly Bottom")
	)
	(footprint ""
		(layer "F.Cu")
		(at 45.275246 -248.0437 90)
		(property "Reference" "R198"
			(at 0 0 90)
			(layer "F.SilkS")
			(hide yes)
			(effects
				(font
					(size 1.27 1.27)
				)
			)
		)
		(property "Value" "10KR2F-2-GP"
			(at 0.064008 -3.993896 90)
			(unlocked yes)
			(layer "F.Fab")
			(hide yes)
			(effects
				(font
					(size 1.016 1.016)
					(thickness 0.1524)
				)
			)
		)
		(property "Device Type" "R402H16"
			(at 0.064008 -5.517896 90)
			(unlocked yes)
			(layer "F.Fab")
			(hide yes)
			(effects
				(font
					(size 1.016 1.016)
					(thickness 0.1524)
				)
			)
		)
		(duplicate_pad_numbers_are_jumpers no)
		(fp_line
			(start 0.508 -0.9398)
			(end -0.508 -0.9398)
			(stroke
				(width 0.1524)
				(type default)
			)
			(layer "F.SilkS")
		)
		(fp_line
			(start -0.508 -0.9398)
			(end -0.508 0.9398)
			(stroke
				(width 0.1524)
				(type default)
			)
			(layer "F.SilkS")
		)
		(fp_rect
			(start -0.508 0.9398)
			(end 0.508 -0.9398)
			(stroke
				(width 0)
				(type default)
			)
			(fill no)
			(layer "F.CrtYd")
		)
		(fp_rect
			(start -0.508 0.9398)
			(end 0.508 -0.9398)
			(stroke
				(width 0)
				(type default)
			)
			(fill no)
			(layer "F.Fab")
		)
		(pad "1" smd custom
			(at 0 -0.4445 90)
			(size 0.1397 0.1397)
			(layers "F.Cu" "F.Mask" "F.Paste")
			(net "P5VB")
			(options
				(clearance outline)
				(anchor circle)
			)
			(primitives
				(gr_poly
					(pts
						(arc
							(start -0.1778 -0.2794)
							(mid -0.249642 -0.249642)
							(end -0.2794 -0.1778)
						)
						(arc
							(start -0.2794 0.1778)
							(mid -0.249642 0.249642)
							(end -0.1778 0.2794)
						)
						(arc
							(start 0.1778 0.2794)
							(mid 0.249642 0.249642)
							(end 0.2794 0.1778)
						)
						(arc
							(start 0.2794 -0.1778)
							(mid 0.249642 -0.249642)
							(end 0.1778 -0.2794)
						)
					)
					(width 0)
					(fill yes)
				)
			)
		)
		(pad "2" smd custom
			(at 0 0.4445 90)
			(size 0.1397 0.1397)
			(layers "F.Cu" "F.Mask" "F.Paste")
			(net "DRIVE_ACT_7")
			(options
				(clearance outline)
				(anchor circle)
			)
			(primitives
				(gr_poly
					(pts
						(arc
							(start -0.1778 -0.2794)
							(mid -0.249642 -0.249642)
							(end -0.2794 -0.1778)
						)
						(arc
							(start -0.2794 0.1778)
							(mid -0.249642 0.249642)
							(end -0.1778 0.2794)
						)
						(arc
							(start 0.1778 0.2794)
							(mid 0.249642 0.249642)
							(end 0.2794 0.1778)
						)
						(arc
							(start 0.2794 -0.1778)
							(mid 0.249642 -0.249642)
							(end 0.1778 -0.2794)
						)
					)
					(width 0)
					(fill yes)
				)
			)
		)
	)
	(footprint ""
		(layer "F.Cu")
		(at 5.969 -30.353 -90)
		(property "Reference" "C157"
			(at 0 0 270)
			(layer "F.SilkS")
			(hide yes)
			(effects
				(font
					(size 1.27 1.27)
				)
			)
		)
		(property "Value" "SC1U25V3KX-1-GP"
			(at 0 -2.8194 270)
			(unlocked yes)
			(layer "F.Fab")
			(hide yes)
			(effects
				(font
					(size 1.016 1.016)
					(thickness 0.1524)
				)
			)
		)
		(property "Device Type" "C603H36"
			(at 0 -4.3434 270)
			(unlocked yes)
			(layer "F.Fab")
			(hide yes)
			(effects
				(font
					(size 1.016 1.016)
					(thickness 0.1524)
				)
			)
		)
		(duplicate_pad_numbers_are_jumpers no)
		(fp_line
			(start 0.508 0)
			(end -0.508 0)
			(stroke
				(width 0.2032)
				(type default)
			)
			(layer "F.SilkS")
		)
		(fp_rect
			(start -0.5842 1.3335)
			(end 0.5842 -1.3335)
			(stroke
				(width 0)
				(type default)
			)
			(fill no)
			(layer "F.CrtYd")
		)
		(fp_rect
			(start -0.5842 1.3335)
			(end 0.5842 -1.3335)
			(stroke
				(width 0)
				(type default)
			)
			(fill no)
			(layer "F.Fab")
		)
		(pad "1" smd custom
			(at 0 -0.762 270)
			(size 0.2159 0.2159)
			(layers "F.Cu" "F.Mask" "F.Paste")
			(net "P12V")
			(options
				(clearance outline)
				(anchor circle)
			)
			(primitives
				(gr_poly
					(pts
						(arc
							(start -0.3302 -0.4318)
							(mid -0.402042 -0.402042)
							(end -0.4318 -0.3302)
						)
						(arc
							(start -0.4318 0.3302)
							(mid -0.402042 0.402042)
							(end -0.3302 0.4318)
						)
						(arc
							(start 0.3302 0.4318)
							(mid 0.402042 0.402042)
							(end 0.4318 0.3302)
						)
						(arc
							(start 0.4318 -0.3302)
							(mid 0.402042 -0.402042)
							(end 0.3302 -0.4318)
						)
					)
					(width 0)
					(fill yes)
				)
			)
		)
		(pad "2" smd custom
			(at 0 0.762 270)
			(size 0.2159 0.2159)
			(layers "F.Cu" "F.Mask" "F.Paste")
			(net "GND")
			(options
				(clearance outline)
				(anchor circle)
			)
			(primitives
				(gr_poly
					(pts
						(arc
							(start -0.3302 -0.4318)
							(mid -0.402042 -0.402042)
							(end -0.4318 -0.3302)
						)
						(arc
							(start -0.4318 0.3302)
							(mid -0.402042 0.402042)
							(end -0.3302 0.4318)
						)
						(arc
							(start 0.3302 0.4318)
							(mid 0.402042 0.402042)
							(end 0.4318 0.3302)
						)
						(arc
							(start 0.4318 -0.3302)
							(mid 0.402042 -0.402042)
							(end 0.3302 -0.4318)
						)
					)
					(width 0)
					(fill yes)
				)
			)
		)
	)
	(footprint ""
		(layer "F.Cu")
		(at 77.216 -23.0378 90)
		(property "Reference" "R404"
			(at 0 0 90)
			(layer "F.SilkS")
			(hide yes)
			(effects
				(font
					(size 1.27 1.27)
				)
			)
		)
		(property "Value" "0R2J-2-GP"
			(at 0.064008 -3.993896 90)
			(unlocked yes)
			(layer "F.Fab")
			(hide yes)
			(effects
				(font
					(size 1.016 1.016)
					(thickness 0.1524)
				)
			)
		)
		(property "Device Type" "R402H16"
			(at 0.064008 -5.517896 90)
			(unlocked yes)
			(layer "F.Fab")
			(hide yes)
			(effects
				(font
					(size 1.016 1.016)
					(thickness 0.1524)
				)
			)
		)
		(duplicate_pad_numbers_are_jumpers no)
		(fp_line
			(start 0.508 -0.9398)
			(end -0.508 -0.9398)
			(stroke
				(width 0.1524)
				(type default)
			)
			(layer "F.SilkS")
		)
		(fp_line
			(start -0.508 -0.9398)
			(end -0.508 0.9398)
			(stroke
				(width 0.1524)
				(type default)
			)
			(layer "F.SilkS")
		)
		(fp_rect
			(start -0.508 0.9398)
			(end 0.508 -0.9398)
			(stroke
				(width 0)
				(type default)
			)
			(fill no)
			(layer "F.CrtYd")
		)
		(fp_rect
			(start -0.508 0.9398)
			(end 0.508 -0.9398)
			(stroke
				(width 0)
				(type default)
			)
			(fill no)
			(layer "F.Fab")
		)
		(pad "1" smd custom
			(at 0 -0.4445 90)
			(size 0.1397 0.1397)
			(layers "F.Cu" "F.Mask" "F.Paste")
			(net "HDD_PRSNT_NET14")
			(options
				(clearance outline)
				(anchor circle)
			)
			(primitives
				(gr_poly
					(pts
						(arc
							(start -0.1778 -0.2794)
							(mid -0.249642 -0.249642)
							(end -0.2794 -0.1778)
						)
						(arc
							(start -0.2794 0.1778)
							(mid -0.249642 0.249642)
							(end -0.1778 0.2794)
						)
						(arc
							(start 0.1778 0.2794)
							(mid 0.249642 0.249642)
							(end 0.2794 0.1778)
						)
						(arc
							(start 0.2794 -0.1778)
							(mid 0.249642 -0.249642)
							(end 0.1778 -0.2794)
						)
					)
					(width 0)
					(fill yes)
				)
			)
		)
		(pad "2" smd custom
			(at 0 0.4445 90)
			(size 0.1397 0.1397)
			(layers "F.Cu" "F.Mask" "F.Paste")
			(net "HDD14_LED_B")
			(options
				(clearance outline)
				(anchor circle)
			)
			(primitives
				(gr_poly
					(pts
						(arc
							(start -0.1778 -0.2794)
							(mid -0.249642 -0.249642)
							(end -0.2794 -0.1778)
						)
						(arc
							(start -0.2794 0.1778)
							(mid -0.249642 0.249642)
							(end -0.1778 0.2794)
						)
						(arc
							(start 0.1778 0.2794)
							(mid 0.249642 0.249642)
							(end 0.2794 0.1778)
						)
						(arc
							(start 0.2794 -0.1778)
							(mid 0.249642 -0.249642)
							(end 0.1778 -0.2794)
						)
					)
					(width 0)
					(fill yes)
				)
			)
		)
	)
	(footprint ""
		(layer "F.Cu")
		(at 215.273382 -291.310568 180)
		(property "Reference" "C144"
			(at 0 0 180)
			(layer "F.SilkS")
			(hide yes)
			(effects
				(font
					(size 1.27 1.27)
				)
			)
		)
		(property "Value" "SC10U25V6KX-1GP"
			(at -0.0762 -5.1308 180)
			(unlocked yes)
			(layer "F.Fab")
			(hide yes)
			(effects
				(font
					(size 1.016 1.016)
					(thickness 0.1524)
				)
			)
		)
		(property "Device Type" "C1206H71"
			(at -0.127 -6.6548 180)
			(unlocked yes)
			(layer "F.Fab")
			(hide yes)
			(effects
				(font
					(size 1.016 1.016)
					(thickness 0.1524)
				)
			)
		)
		(duplicate_pad_numbers_are_jumpers no)
		(fp_line
			(start 1.016 2.2352)
			(end -1.016 2.2352)
			(stroke
				(width 0.1524)
				(type default)
			)
			(layer "F.SilkS")
		)
		(fp_line
			(start 1.016 0.8382)
			(end 1.016 2.2352)
			(stroke
				(width 0.1524)
				(type default)
			)
			(layer "F.SilkS")
		)
		(fp_line
			(start 1.016 -2.2352)
			(end 1.016 -0.8382)
			(stroke
				(width 0.1524)
				(type default)
			)
			(layer "F.SilkS")
		)
		(fp_line
			(start -1.016 2.2352)
			(end -1.016 0.8382)
			(stroke
				(width 0.1524)
				(type default)
			)
			(layer "F.SilkS")
		)
		(fp_line
			(start -1.016 -0.8382)
			(end -1.016 -2.2352)
			(stroke
				(width 0.1524)
				(type default)
			)
			(layer "F.SilkS")
		)
		(fp_line
			(start -1.016 -2.2352)
			(end 1.016 -2.2352)
			(stroke
				(width 0.1524)
				(type default)
			)
			(layer "F.SilkS")
		)
		(fp_rect
			(start -1.0922 2.3114)
			(end 1.0922 -2.3114)
			(stroke
				(width 0)
				(type default)
			)
			(fill no)
			(layer "F.CrtYd")
		)
		(fp_poly
			(pts
				(xy 1.0922 -2.3114) (xy 1.0922 2.3114) (xy -1.0922 2.3114) (xy -1.0922 -2.3114)
			)
			(stroke
				(width 0)
				(type default)
			)
			(fill no)
			(layer "F.Fab")
		)
		(pad "1" smd rect
			(at 0 -1.397 180)
			(size 1.651 1.27)
			(layers "F.Cu" "F.Mask" "F.Paste")
			(net "P12V_HDD2")
		)
		(pad "2" smd rect
			(at 0 1.397 180)
			(size 1.651 1.27)
			(layers "F.Cu" "F.Mask" "F.Paste")
			(net "GND")
		)
	)
	(footprint ""
		(layer "F.Cu")
		(at 58.674 -478.0788)
		(property "Reference" "R375"
			(at 0 0 0)
			(layer "F.SilkS")
			(hide yes)
			(effects
				(font
					(size 1.27 1.27)
				)
			)
		)
		(property "Value" "10KR2F-2-GP"
			(at 0.064008 -3.993896 0)
			(unlocked yes)
			(layer "F.Fab")
			(hide yes)
			(effects
				(font
					(size 1.016 1.016)
					(thickness 0.1524)
				)
			)
		)
		(property "Device Type" "R402H16"
			(at 0.064008 -5.517896 0)
			(unlocked yes)
			(layer "F.Fab")
			(hide yes)
			(effects
				(font
					(size 1.016 1.016)
					(thickness 0.1524)
				)
			)
		)
		(duplicate_pad_numbers_are_jumpers no)
		(fp_line
			(start -0.508 -0.9398)
			(end -0.508 0.9398)
			(stroke
				(width 0.1524)
				(type default)
			)
			(layer "F.SilkS")
		)
		(fp_line
			(start 0.508 -0.9398)
			(end -0.508 -0.9398)
			(stroke
				(width 0.1524)
				(type default)
			)
			(layer "F.SilkS")
		)
		(fp_rect
			(start -0.508 0.9398)
			(end 0.508 -0.9398)
			(stroke
				(width 0)
				(type default)
			)
			(fill no)
			(layer "F.CrtYd")
		)
		(fp_rect
			(start -0.508 0.9398)
			(end 0.508 -0.9398)
			(stroke
				(width 0)
				(type default)
			)
			(fill no)
			(layer "F.Fab")
		)
		(pad "1" smd custom
			(at 0 -0.4445)
			(size 0.1397 0.1397)
			(layers "F.Cu" "F.Mask" "F.Paste")
			(net "P12V")
			(options
				(clearance outline)
				(anchor circle)
			)
			(primitives
				(gr_poly
					(pts
						(arc
							(start -0.1778 -0.2794)
							(mid -0.249642 -0.249642)
							(end -0.2794 -0.1778)
						)
						(arc
							(start -0.2794 0.1778)
							(mid -0.249642 0.249642)
							(end -0.1778 0.2794)
						)
						(arc
							(start 0.1778 0.2794)
							(mid 0.249642 0.249642)
							(end 0.2794 0.1778)
						)
						(arc
							(start 0.2794 -0.1778)
							(mid 0.249642 -0.249642)
							(end 0.1778 -0.2794)
						)
					)
					(width 0)
					(fill yes)
				)
			)
		)
		(pad "2" smd custom
			(at 0 0.4445)
			(size 0.1397 0.1397)
			(layers "F.Cu" "F.Mask" "F.Paste")
			(net "HDD5_LED_G")
			(options
				(clearance outline)
				(anchor circle)
			)
			(primitives
				(gr_poly
					(pts
						(arc
							(start -0.1778 -0.2794)
							(mid -0.249642 -0.249642)
							(end -0.2794 -0.1778)
						)
						(arc
							(start -0.2794 0.1778)
							(mid -0.249642 0.249642)
							(end -0.1778 0.2794)
						)
						(arc
							(start 0.1778 0.2794)
							(mid 0.249642 0.249642)
							(end 0.2794 0.1778)
						)
						(arc
							(start 0.2794 -0.1778)
							(mid 0.249642 -0.249642)
							(end 0.1778 -0.2794)
						)
					)
					(width 0)
					(fill yes)
				)
			)
		)
	)
	(footprint ""
		(layer "F.Cu")
		(at 227.837746 -33.2867 180)
		(property "Reference" "PC12"
			(at 0 0 180)
			(layer "F.SilkS")
			(hide yes)
			(effects
				(font
					(size 1.27 1.27)
				)
			)
		)
		(property "Value" "SC10U16V6KX-2GP"
			(at -0.0762 -5.1308 180)
			(unlocked yes)
			(layer "F.Fab")
			(hide yes)
			(effects
				(font
					(size 1.016 1.016)
					(thickness 0.1524)
				)
			)
		)
		(property "Device Type" "C1206H71"
			(at -0.127 -6.6548 180)
			(unlocked yes)
			(layer "F.Fab")
			(hide yes)
			(effects
				(font
					(size 1.016 1.016)
					(thickness 0.1524)
				)
			)
		)
		(duplicate_pad_numbers_are_jumpers no)
		(fp_line
			(start 1.016 2.2352)
			(end -1.016 2.2352)
			(stroke
				(width 0.1524)
				(type default)
			)
			(layer "F.SilkS")
		)
		(fp_line
			(start 1.016 0.8382)
			(end 1.016 2.2352)
			(stroke
				(width 0.1524)
				(type default)
			)
			(layer "F.SilkS")
		)
		(fp_line
			(start 1.016 -2.2352)
			(end 1.016 -0.8382)
			(stroke
				(width 0.1524)
				(type default)
			)
			(layer "F.SilkS")
		)
		(fp_line
			(start -1.016 2.2352)
			(end -1.016 0.8382)
			(stroke
				(width 0.1524)
				(type default)
			)
			(layer "F.SilkS")
		)
		(fp_line
			(start -1.016 -0.8382)
			(end -1.016 -2.2352)
			(stroke
				(width 0.1524)
				(type default)
			)
			(layer "F.SilkS")
		)
		(fp_line
			(start -1.016 -2.2352)
			(end 1.016 -2.2352)
			(stroke
				(width 0.1524)
				(type default)
			)
			(layer "F.SilkS")
		)
		(fp_rect
			(start -1.0922 2.3114)
			(end 1.0922 -2.3114)
			(stroke
				(width 0)
				(type default)
			)
			(fill no)
			(layer "F.CrtYd")
		)
		(fp_poly
			(pts
				(xy 1.0922 -2.3114) (xy 1.0922 2.3114) (xy -1.0922 2.3114) (xy -1.0922 -2.3114)
			)
			(stroke
				(width 0)
				(type default)
			)
			(fill no)
			(layer "F.Fab")
		)
		(pad "1" smd rect
			(at 0 -1.397 180)
			(size 1.651 1.27)
			(layers "F.Cu" "F.Mask" "F.Paste")
			(net "P5VA")
		)
		(pad "2" smd rect
			(at 0 1.397 180)
			(size 1.651 1.27)
			(layers "F.Cu" "F.Mask" "F.Paste")
			(net "GND")
		)
	)
	(footprint ""
		(layer "F.Cu")
		(at 99.313746 -13.6017 90)
		(property "Reference" "U45"
			(at 0 0 90)
			(layer "F.SilkS")
			(hide yes)
			(effects
				(font
					(size 1.27 1.27)
				)
			)
		)
		(property "Value" "74LVC1G08GW-1-GP"
			(at -2.3368 -8.6868 90)
			(unlocked yes)
			(layer "F.Fab")
			(hide yes)
			(effects
				(font
					(size 1.016 1.016)
					(thickness 0.1524)
				)
			)
		)
		(property "Device Type" "SC70-5H44"
			(at -2.3114 -10.414 90)
			(unlocked yes)
			(layer "F.Fab")
			(hide yes)
			(effects
				(font
					(size 1.016 1.016)
					(thickness 0.1524)
				)
			)
		)
		(duplicate_pad_numbers_are_jumpers no)
		(fp_line
			(start 1.3843 -1.8034)
			(end 1.3843 -1.1176)
			(stroke
				(width 0.3302)
				(type default)
			)
			(layer "F.SilkS")
		)
		(fp_line
			(start 0.6604 -1.8034)
			(end 1.3843 -1.8034)
			(stroke
				(width 0.3302)
				(type default)
			)
			(layer "F.SilkS")
		)
		(fp_line
			(start 1.27 -1.7018)
			(end 1.27 1.7018)
			(stroke
				(width 0.1524)
				(type default)
			)
			(layer "F.SilkS")
		)
		(fp_line
			(start -1.27 -1.7018)
			(end 1.27 -1.7018)
			(stroke
				(width 0.1524)
				(type default)
			)
			(layer "F.SilkS")
		)
		(fp_line
			(start 1.27 1.7018)
			(end -1.27 1.7018)
			(stroke
				(width 0.1524)
				(type default)
			)
			(layer "F.SilkS")
		)
		(fp_line
			(start -1.27 1.7018)
			(end -1.27 -1.7018)
			(stroke
				(width 0.1524)
				(type default)
			)
			(layer "F.SilkS")
		)
		(fp_rect
			(start -1.524 1.9558)
			(end 1.524 -1.9558)
			(stroke
				(width 0)
				(type default)
			)
			(fill no)
			(layer "F.CrtYd")
		)
		(fp_poly
			(pts
				(xy -1.524 -1.9558) (xy 1.524 -1.9558) (xy 1.524 1.9558) (xy -1.524 1.9558)
			)
			(stroke
				(width 0)
				(type default)
			)
			(fill no)
			(layer "F.Fab")
		)
		(pad "1" smd rect
			(at 0.65024 -0.8255 90)
			(size 0.4064 1.2192)
			(layers "F.Cu" "F.Mask" "F.Paste")
			(net "SAS_EXP_B_PWR14")
		)
		(pad "2" smd rect
			(at 0 -0.8255 90)
			(size 0.4064 1.2192)
			(layers "F.Cu" "F.Mask" "F.Paste")
			(net "SAS_EXP_A_PWR14")
		)
		(pad "3" smd rect
			(at -0.65024 -0.8255 90)
			(size 0.4064 1.2192)
			(layers "F.Cu" "F.Mask" "F.Paste")
			(net "GND")
		)
		(pad "4" smd rect
			(at -0.65024 0.8255 90)
			(size 0.4064 1.2192)
			(layers "F.Cu" "F.Mask" "F.Paste")
			(net "DRIVE_PWR14")
		)
		(pad "5" smd rect
			(at 0.65024 0.8255 90)
			(size 0.4064 1.2192)
			(layers "F.Cu" "F.Mask" "F.Paste")
			(net "P3V3")
		)
	)
	(footprint ""
		(layer "F.Cu")
		(at 176.161446 -459.139036)
		(property "Reference" "C362"
			(at 0 0 0)
			(layer "F.SilkS")
			(hide yes)
			(effects
				(font
					(size 1.27 1.27)
				)
			)
		)
		(property "Value" "SCD1U16V2KX-3GP"
			(at 1.1811 -2.7051 0)
			(unlocked yes)
			(layer "F.Fab")
			(hide yes)
			(effects
				(font
					(size 1.016 1.016)
					(thickness 0.1524)
				)
			)
		)
		(property "Device Type" "C402H22"
			(at 1.1811 -4.2291 0)
			(unlocked yes)
			(layer "F.Fab")
			(hide yes)
			(effects
				(font
					(size 1.016 1.016)
					(thickness 0.1524)
				)
			)
		)
		(duplicate_pad_numbers_are_jumpers no)
		(fp_rect
			(start -0.4318 0.9525)
			(end 0.4318 -0.9525)
			(stroke
				(width 0)
				(type default)
			)
			(fill no)
			(layer "F.CrtYd")
		)
		(fp_rect
			(start -0.4318 0.9525)
			(end 0.4318 -0.9525)
			(stroke
				(width 0)
				(type default)
			)
			(fill no)
			(layer "F.Fab")
		)
		(pad "1" smd custom
			(at 0 -0.4445)
			(size 0.1524 0.1524)
			(layers "F.Cu" "F.Mask" "F.Paste")
			(net "P12V_SENSE")
			(options
				(clearance outline)
				(anchor circle)
			)
			(primitives
				(gr_poly
					(pts
						(arc
							(start 0.3048 -0.2032)
							(mid 0.275042 -0.275042)
							(end 0.2032 -0.3048)
						)
						(arc
							(start -0.2032 -0.3048)
							(mid -0.275042 -0.275042)
							(end -0.3048 -0.2032)
						)
						(arc
							(start -0.3048 0.2032)
							(mid -0.275042 0.275042)
							(end -0.2032 0.3048)
						)
						(arc
							(start 0.2032 0.3048)
							(mid 0.275042 0.275042)
							(end 0.3048 0.2032)
						)
					)
					(width 0)
					(fill yes)
				)
			)
		)
		(pad "2" smd custom
			(at 0 0.4445)
			(size 0.1524 0.1524)
			(layers "F.Cu" "F.Mask" "F.Paste")
			(net "GND")
			(options
				(clearance outline)
				(anchor circle)
			)
			(primitives
				(gr_poly
					(pts
						(arc
							(start 0.3048 -0.2032)
							(mid 0.275042 -0.275042)
							(end 0.2032 -0.3048)
						)
						(arc
							(start -0.2032 -0.3048)
							(mid -0.275042 -0.275042)
							(end -0.3048 -0.2032)
						)
						(arc
							(start -0.3048 0.2032)
							(mid -0.275042 0.275042)
							(end -0.2032 0.3048)
						)
						(arc
							(start 0.2032 0.3048)
							(mid 0.275042 0.275042)
							(end 0.3048 0.2032)
						)
					)
					(width 0)
					(fill yes)
				)
			)
		)
	)
)
